(kicad_pcb
	(version 20260206)
	(generator "pcbnew")
	(generator_version "10.0")
	(general
		(thickness 1.6)
		(legacy_teardrops no)
	)
	(paper "A4")
	(title_block
		(title "04192023_DAF0TMB3IC0_F0TG_MB_C_brd_V02_OCP.brd")
		(comment 1 "Grand Teton / footprints 3401-3406 of 8354")
	)
	(layers
		(0 "F.Cu" signal "TOP")
		(4 "In1.Cu" signal "GND")
		(6 "In2.Cu" signal "IN1")
		(8 "In3.Cu" signal "GND1")
		(10 "In4.Cu" signal "IN2")
		(12 "In5.Cu" signal "GND2")
		(14 "In6.Cu" signal "IN3")
		(16 "In7.Cu" signal "GND3")
		(18 "In8.Cu" signal "VCC")
		(20 "In9.Cu" signal "VCC1")
		(22 "In10.Cu" signal "GND4")
		(24 "In11.Cu" signal "IN4")
		(26 "In12.Cu" signal "GND5")
		(28 "In13.Cu" signal "IN5")
		(30 "In14.Cu" signal "GND6")
		(32 "In15.Cu" signal "IN6")
		(34 "In16.Cu" signal "GND7")
		(2 "B.Cu" signal "BOTTOM")
		(9 "F.Adhes" user "F.Adhesive")
		(11 "B.Adhes" user "B.Adhesive")
		(13 "F.Paste" user "Package Geometry/Pastemask Top")
		(15 "B.Paste" user "Package Geometry/Pastemask Bottom")
		(5 "F.SilkS" user "Ref Des/Silkscreen Top")
		(7 "B.SilkS" user "Ref Des/Silkscreen Bottom")
		(1 "F.Mask" user "Board Geometry/Soldermask Top")
		(3 "B.Mask" user "Board Geometry/Soldermask Bottom")
		(17 "Dwgs.User" user "User.Drawings")
		(19 "Cmts.User" user "User.Comments")
		(21 "Eco1.User" user "User.Eco1")
		(23 "Eco2.User" user "User.Eco2")
		(25 "Edge.Cuts" user "Board Geometry/Outline")
		(27 "Margin" user)
		(31 "F.CrtYd" user "Package Geometry/Place Bound Top")
		(29 "B.CrtYd" user "Package Geometry/Place Bound Bottom")
		(35 "F.Fab" user "Ref Des/Assembly Top")
		(33 "B.Fab" user "Ref Des/Assembly Bottom")
	)
	(footprint ""
		(layer "F.Cu")
		(at 140.446252 -60.849764 180)
		(property "Reference" "R1744"
			(at 0 0 180)
			(layer "F.SilkS")
			(hide yes)
			(effects
				(font
					(size 1.27 1.27)
				)
			)
		)
		(property "Value" ""
			(at 0 0 180)
			(layer "F.Fab")
			(effects
				(font
					(size 1.27 1.27)
				)
			)
		)
		(duplicate_pad_numbers_are_jumpers no)
		(fp_line
			(start 0.7874 0.4064)
			(end -0.7874 0.4064)
			(stroke
				(width 0.1524)
				(type default)
			)
			(layer "F.SilkS")
		)
		(fp_line
			(start 0.7874 -0.4064)
			(end 0.7874 0.4064)
			(stroke
				(width 0.1524)
				(type default)
			)
			(layer "F.SilkS")
		)
		(fp_line
			(start -0.7874 0.4064)
			(end -0.7874 -0.4064)
			(stroke
				(width 0.1524)
				(type default)
			)
			(layer "F.SilkS")
		)
		(fp_line
			(start -0.7874 -0.4064)
			(end 0.7874 -0.4064)
			(stroke
				(width 0.1524)
				(type default)
			)
			(layer "F.SilkS")
		)
		(fp_line
			(start 0.67945 0.3048)
			(end 0.120396 0.3048)
			(stroke
				(width 0.1)
				(type default)
			)
			(layer "F.Fab")
		)
		(fp_line
			(start 0.67945 -0.3048)
			(end 0.67945 0.3048)
			(stroke
				(width 0.1)
				(type default)
			)
			(layer "F.Fab")
		)
		(fp_line
			(start 0.12065 -0.2794)
			(end 0.12065 -0.3048)
			(stroke
				(width 0.1)
				(type default)
			)
			(layer "F.Fab")
		)
		(fp_line
			(start 0.12065 -0.3048)
			(end 0.67945 -0.3048)
			(stroke
				(width 0.1)
				(type default)
			)
			(layer "F.Fab")
		)
		(fp_line
			(start 0.120396 0.3048)
			(end 0.120396 0.2794)
			(stroke
				(width 0.1)
				(type default)
			)
			(layer "F.Fab")
		)
		(fp_line
			(start 0.120396 0.2794)
			(end -0.12065 0.2794)
			(stroke
				(width 0.1)
				(type default)
			)
			(layer "F.Fab")
		)
		(fp_line
			(start -0.12065 0.3048)
			(end -0.67945 0.3048)
			(stroke
				(width 0.1)
				(type default)
			)
			(layer "F.Fab")
		)
		(fp_line
			(start -0.12065 0.2794)
			(end -0.12065 0.3048)
			(stroke
				(width 0.1)
				(type default)
			)
			(layer "F.Fab")
		)
		(fp_line
			(start -0.12065 -0.2794)
			(end 0.12065 -0.2794)
			(stroke
				(width 0.1)
				(type default)
			)
			(layer "F.Fab")
		)
		(fp_line
			(start -0.12065 -0.305054)
			(end -0.12065 -0.2794)
			(stroke
				(width 0.1)
				(type default)
			)
			(layer "F.Fab")
		)
		(fp_line
			(start -0.67945 0.3048)
			(end -0.67945 -0.305054)
			(stroke
				(width 0.1)
				(type default)
			)
			(layer "F.Fab")
		)
		(fp_line
			(start -0.67945 -0.305054)
			(end -0.12065 -0.305054)
			(stroke
				(width 0.1)
				(type default)
			)
			(layer "F.Fab")
		)
		(pad "1" smd circle
			(at -0.40005 0 180)
			(size 0 0)
			(layers "F.Cu" "F.Mask" "F.Paste")
			(net "P3V3_AUX")
		)
		(pad "2" smd circle
			(at 0.40005 0 180)
			(size 0 0)
			(layers "F.Cu" "F.Mask" "F.Paste")
			(net "JTAG_SCM_MUX_TDI")
		)
	)
	(footprint ""
		(layer "F.Cu")
		(at 426.332396 -392.9888 180)
		(property "Reference" "L18"
			(at 0 0 180)
			(layer "F.SilkS")
			(hide yes)
			(effects
				(font
					(size 1.27 1.27)
				)
			)
		)
		(property "Value" ""
			(at 0 0 180)
			(layer "F.Fab")
			(effects
				(font
					(size 1.27 1.27)
				)
			)
		)
		(duplicate_pad_numbers_are_jumpers no)
		(fp_line
			(start 1.63576 0.8128)
			(end -1.63576 0.8128)
			(stroke
				(width 0.1524)
				(type default)
			)
			(layer "F.SilkS")
		)
		(fp_line
			(start 1.63576 -0.8128)
			(end 1.63576 0.8128)
			(stroke
				(width 0.1524)
				(type default)
			)
			(layer "F.SilkS")
		)
		(fp_line
			(start -1.63576 -0.8128)
			(end 1.63576 -0.8128)
			(stroke
				(width 0.1524)
				(type default)
			)
			(layer "F.SilkS")
		)
		(fp_line
			(start -1.63576 -0.8128)
			(end -1.63576 0.8128)
			(stroke
				(width 0.1524)
				(type default)
			)
			(layer "F.SilkS")
		)
		(fp_line
			(start 1.560576 0.7366)
			(end 1.560576 -0.738632)
			(stroke
				(width 0.1)
				(type default)
			)
			(layer "F.Fab")
		)
		(fp_line
			(start 1.560576 -0.738632)
			(end -1.56083 -0.738632)
			(stroke
				(width 0.1)
				(type default)
			)
			(layer "F.Fab")
		)
		(fp_line
			(start 1.524 0.7366)
			(end 1.560576 0.7366)
			(stroke
				(width 0.1)
				(type default)
			)
			(layer "F.Fab")
		)
		(fp_line
			(start -1.524 0.7366)
			(end 1.524 0.7366)
			(stroke
				(width 0.1)
				(type default)
			)
			(layer "F.Fab")
		)
		(fp_line
			(start -1.56083 0.7366)
			(end -1.524 0.7366)
			(stroke
				(width 0.1)
				(type default)
			)
			(layer "F.Fab")
		)
		(fp_line
			(start -1.56083 -0.738632)
			(end -1.56083 0.7366)
			(stroke
				(width 0.1)
				(type default)
			)
			(layer "F.Fab")
		)
		(pad "1" smd rect
			(at -0.94996 0)
			(size 1.1176 1.3716)
			(layers "F.Cu" "F.Mask" "F.Paste")
			(net "P1V8_CPU0_RT_1D")
		)
		(pad "2" smd rect
			(at 0.94996 0)
			(size 1.1176 1.3716)
			(layers "F.Cu" "F.Mask" "F.Paste")
			(net "P1V8_CPU0_RT2_1A")
		)
	)
	(footprint ""
		(layer "F.Cu")
		(at 200.939908 -105.497376)
		(property "Reference" "R227"
			(at 0 0 0)
			(layer "F.SilkS")
			(hide yes)
			(effects
				(font
					(size 1.27 1.27)
				)
			)
		)
		(property "Value" ""
			(at 0 0 0)
			(layer "F.Fab")
			(effects
				(font
					(size 1.27 1.27)
				)
			)
		)
		(duplicate_pad_numbers_are_jumpers no)
		(fp_line
			(start -0.7874 -0.4064)
			(end 0.7874 -0.4064)
			(stroke
				(width 0.1524)
				(type default)
			)
			(layer "F.SilkS")
		)
		(fp_line
			(start -0.7874 0.4064)
			(end -0.7874 -0.4064)
			(stroke
				(width 0.1524)
				(type default)
			)
			(layer "F.SilkS")
		)
		(fp_line
			(start 0.7874 -0.4064)
			(end 0.7874 0.4064)
			(stroke
				(width 0.1524)
				(type default)
			)
			(layer "F.SilkS")
		)
		(fp_line
			(start 0.7874 0.4064)
			(end -0.7874 0.4064)
			(stroke
				(width 0.1524)
				(type default)
			)
			(layer "F.SilkS")
		)
		(fp_line
			(start -0.67945 -0.305054)
			(end -0.12065 -0.305054)
			(stroke
				(width 0.1)
				(type default)
			)
			(layer "F.Fab")
		)
		(fp_line
			(start -0.67945 0.3048)
			(end -0.67945 -0.305054)
			(stroke
				(width 0.1)
				(type default)
			)
			(layer "F.Fab")
		)
		(fp_line
			(start -0.12065 -0.305054)
			(end -0.12065 -0.2794)
			(stroke
				(width 0.1)
				(type default)
			)
			(layer "F.Fab")
		)
		(fp_line
			(start -0.12065 -0.2794)
			(end 0.12065 -0.2794)
			(stroke
				(width 0.1)
				(type default)
			)
			(layer "F.Fab")
		)
		(fp_line
			(start -0.12065 0.2794)
			(end -0.12065 0.3048)
			(stroke
				(width 0.1)
				(type default)
			)
			(layer "F.Fab")
		)
		(fp_line
			(start -0.12065 0.3048)
			(end -0.67945 0.3048)
			(stroke
				(width 0.1)
				(type default)
			)
			(layer "F.Fab")
		)
		(fp_line
			(start 0.120396 0.2794)
			(end -0.12065 0.2794)
			(stroke
				(width 0.1)
				(type default)
			)
			(layer "F.Fab")
		)
		(fp_line
			(start 0.120396 0.3048)
			(end 0.120396 0.2794)
			(stroke
				(width 0.1)
				(type default)
			)
			(layer "F.Fab")
		)
		(fp_line
			(start 0.12065 -0.3048)
			(end 0.67945 -0.3048)
			(stroke
				(width 0.1)
				(type default)
			)
			(layer "F.Fab")
		)
		(fp_line
			(start 0.12065 -0.2794)
			(end 0.12065 -0.3048)
			(stroke
				(width 0.1)
				(type default)
			)
			(layer "F.Fab")
		)
		(fp_line
			(start 0.67945 -0.3048)
			(end 0.67945 0.3048)
			(stroke
				(width 0.1)
				(type default)
			)
			(layer "F.Fab")
		)
		(fp_line
			(start 0.67945 0.3048)
			(end 0.120396 0.3048)
			(stroke
				(width 0.1)
				(type default)
			)
			(layer "F.Fab")
		)
		(pad "1" smd circle
			(at -0.40005 0)
			(size 0 0)
			(layers "F.Cu" "F.Mask" "F.Paste")
			(net "FM_PVDD11_S3_P0_EN")
		)
		(pad "2" smd circle
			(at 0.40005 0)
			(size 0 0)
			(layers "F.Cu" "F.Mask" "F.Paste")
			(net "PVDD11_S3_P0_EN")
		)
	)
	(footprint ""
		(layer "F.Cu")
		(at 353.185222 -425.295314 180)
		(property "Reference" "R4561"
			(at 0 0 180)
			(layer "F.SilkS")
			(hide yes)
			(effects
				(font
					(size 1.27 1.27)
				)
			)
		)
		(property "Value" ""
			(at 0 0 180)
			(layer "F.Fab")
			(effects
				(font
					(size 1.27 1.27)
				)
			)
		)
		(duplicate_pad_numbers_are_jumpers no)
		(fp_line
			(start 0.7874 0.4064)
			(end -0.7874 0.4064)
			(stroke
				(width 0.1524)
				(type default)
			)
			(layer "F.SilkS")
		)
		(fp_line
			(start 0.7874 -0.4064)
			(end 0.7874 0.4064)
			(stroke
				(width 0.1524)
				(type default)
			)
			(layer "F.SilkS")
		)
		(fp_line
			(start -0.7874 0.4064)
			(end -0.7874 -0.4064)
			(stroke
				(width 0.1524)
				(type default)
			)
			(layer "F.SilkS")
		)
		(fp_line
			(start -0.7874 -0.4064)
			(end 0.7874 -0.4064)
			(stroke
				(width 0.1524)
				(type default)
			)
			(layer "F.SilkS")
		)
		(fp_line
			(start 0.67945 0.3048)
			(end 0.120396 0.3048)
			(stroke
				(width 0.1)
				(type default)
			)
			(layer "F.Fab")
		)
		(fp_line
			(start 0.67945 -0.3048)
			(end 0.67945 0.3048)
			(stroke
				(width 0.1)
				(type default)
			)
			(layer "F.Fab")
		)
		(fp_line
			(start 0.12065 -0.2794)
			(end 0.12065 -0.3048)
			(stroke
				(width 0.1)
				(type default)
			)
			(layer "F.Fab")
		)
		(fp_line
			(start 0.12065 -0.3048)
			(end 0.67945 -0.3048)
			(stroke
				(width 0.1)
				(type default)
			)
			(layer "F.Fab")
		)
		(fp_line
			(start 0.120396 0.3048)
			(end 0.120396 0.2794)
			(stroke
				(width 0.1)
				(type default)
			)
			(layer "F.Fab")
		)
		(fp_line
			(start 0.120396 0.2794)
			(end -0.12065 0.2794)
			(stroke
				(width 0.1)
				(type default)
			)
			(layer "F.Fab")
		)
		(fp_line
			(start -0.12065 0.3048)
			(end -0.67945 0.3048)
			(stroke
				(width 0.1)
				(type default)
			)
			(layer "F.Fab")
		)
		(fp_line
			(start -0.12065 0.2794)
			(end -0.12065 0.3048)
			(stroke
				(width 0.1)
				(type default)
			)
			(layer "F.Fab")
		)
		(fp_line
			(start -0.12065 -0.2794)
			(end 0.12065 -0.2794)
			(stroke
				(width 0.1)
				(type default)
			)
			(layer "F.Fab")
		)
		(fp_line
			(start -0.12065 -0.305054)
			(end -0.12065 -0.2794)
			(stroke
				(width 0.1)
				(type default)
			)
			(layer "F.Fab")
		)
		(fp_line
			(start -0.67945 0.3048)
			(end -0.67945 -0.305054)
			(stroke
				(width 0.1)
				(type default)
			)
			(layer "F.Fab")
		)
		(fp_line
			(start -0.67945 -0.305054)
			(end -0.12065 -0.305054)
			(stroke
				(width 0.1)
				(type default)
			)
			(layer "F.Fab")
		)
		(pad "1" smd circle
			(at -0.40005 0 180)
			(size 0 0)
			(layers "F.Cu" "F.Mask" "F.Paste")
			(net "P3V3_AUX")
		)
		(pad "2" smd circle
			(at 0.40005 0 180)
			(size 0 0)
			(layers "F.Cu" "F.Mask" "F.Paste")
			(net "SWB_HSC_PWRGD_ISO")
		)
	)
	(footprint ""
		(layer "F.Cu")
		(at 47.117 -436.372)
		(property "Reference" "U196"
			(at -3.295396 -4.107942 0)
			(unlocked yes)
			(layer "F.SilkS")
			(effects
				(font
					(size 0.7874 0.5842)
					(thickness 0.1524)
				)
				(justify left)
			)
		)
		(property "Value" ""
			(at 0 0 0)
			(layer "F.Fab")
			(effects
				(font
					(size 1.27 1.27)
				)
			)
		)
		(duplicate_pad_numbers_are_jumpers no)
		(fp_line
			(start -1.3462 -1.100074)
			(end -0.670052 -1.100074)
			(stroke
				(width 0.1524)
				(type default)
			)
			(layer "F.SilkS")
		)
		(fp_line
			(start -1.3462 1.100074)
			(end -1.3462 -1.100074)
			(stroke
				(width 0.1524)
				(type default)
			)
			(layer "F.SilkS")
		)
		(fp_line
			(start -0.670052 -1.100074)
			(end 0 -0.381)
			(stroke
				(width 0.1524)
				(type default)
			)
			(layer "F.SilkS")
		)
		(fp_line
			(start 0 -0.381)
			(end 0.670052 -1.100074)
			(stroke
				(width 0.1524)
				(type default)
			)
			(layer "F.SilkS")
		)
		(fp_line
			(start 0.670052 -1.100074)
			(end 1.3462 -1.100074)
			(stroke
				(width 0.1524)
				(type default)
			)
			(layer "F.SilkS")
		)
		(fp_line
			(start 1.3462 -1.100074)
			(end 1.3462 1.100074)
			(stroke
				(width 0.1524)
				(type default)
			)
			(layer "F.SilkS")
		)
		(fp_line
			(start 1.3462 1.100074)
			(end -1.3462 1.100074)
			(stroke
				(width 0.1524)
				(type default)
			)
			(layer "F.SilkS")
		)
		(fp_poly
			(pts
				(xy -2.29108 -1.452372) (xy -1.752346 -1.991106) (xy -1.482852 -1.182878)
			)
			(stroke
				(width 0)
				(type default)
			)
			(fill yes)
			(layer "F.SilkS")
		)
		(fp_line
			(start -1.100074 -0.8001)
			(end -0.670052 -0.8001)
			(stroke
				(width 0.1)
				(type default)
			)
			(layer "F.Fab")
		)
		(fp_line
			(start -1.100074 0.8001)
			(end -1.100074 -0.8001)
			(stroke
				(width 0.1)
				(type default)
			)
			(layer "F.Fab")
		)
		(fp_line
			(start -0.670052 -1.100074)
			(end 0.670052 -1.100074)
			(stroke
				(width 0.1)
				(type default)
			)
			(layer "F.Fab")
		)
		(fp_line
			(start -0.670052 -0.8001)
			(end -0.670052 -1.100074)
			(stroke
				(width 0.1)
				(type default)
			)
			(layer "F.Fab")
		)
		(fp_line
			(start -0.670052 0.8001)
			(end -1.100074 0.8001)
			(stroke
				(width 0.1)
				(type default)
			)
			(layer "F.Fab")
		)
		(fp_line
			(start -0.670052 0.8001)
			(end -0.670052 -0.8001)
			(stroke
				(width 0.1)
				(type default)
			)
			(layer "F.Fab")
		)
		(fp_line
			(start -0.670052 1.100074)
			(end -0.670052 0.8001)
			(stroke
				(width 0.1)
				(type default)
			)
			(layer "F.Fab")
		)
		(fp_line
			(start 0.670052 -1.100074)
			(end 0.670052 -0.8001)
			(stroke
				(width 0.1)
				(type default)
			)
			(layer "F.Fab")
		)
		(fp_line
			(start 0.670052 -0.8001)
			(end 0.670052 0.8001)
			(stroke
				(width 0.1)
				(type default)
			)
			(layer "F.Fab")
		)
		(fp_line
			(start 0.670052 -0.8001)
			(end 1.100074 -0.8001)
			(stroke
				(width 0.1)
				(type default)
			)
			(layer "F.Fab")
		)
		(fp_line
			(start 0.670052 0.8001)
			(end 0.670052 1.100074)
			(stroke
				(width 0.1)
				(type default)
			)
			(layer "F.Fab")
		)
		(fp_line
			(start 0.670052 1.100074)
			(end -0.670052 1.100074)
			(stroke
				(width 0.1)
				(type default)
			)
			(layer "F.Fab")
		)
		(fp_line
			(start 1.100074 -0.8001)
			(end 1.100074 0.8001)
			(stroke
				(width 0.1)
				(type default)
			)
			(layer "F.Fab")
		)
		(fp_line
			(start 1.100074 0.8001)
			(end 0.670052 0.8001)
			(stroke
				(width 0.1)
				(type default)
			)
			(layer "F.Fab")
		)
		(fp_poly
			(pts
				(xy -1.524 -0.649986) (xy -2.286 -1.030986) (xy -2.286 -0.268986)
			)
			(stroke
				(width 0)
				(type default)
			)
			(fill yes)
			(layer "F.Fab")
		)
		(pad "1" smd rect
			(at -0.94996 -0.649986 270)
			(size 0.4064 0.508)
			(layers "F.Cu" "F.Mask" "F.Paste")
			(net "FM_GPU_PWR_EN_R")
		)
		(pad "2" smd rect
			(at -0.94996 0 270)
			(size 0.4064 0.508)
			(layers "F.Cu" "F.Mask" "F.Paste")
			(net "GND")
		)
		(pad "3" smd rect
			(at -0.94996 0.649986 270)
			(size 0.4064 0.508)
			(layers "F.Cu" "F.Mask" "F.Paste")
			(net "GPU_FPGA_RST_R_N")
		)
		(pad "4" smd rect
			(at 0.94996 0.649986 270)
			(size 0.4064 0.508)
			(layers "F.Cu" "F.Mask" "F.Paste")
			(net "GPU_FPGA_RST_R1_BUF_N")
		)
		(pad "5" smd rect
			(at 0.94996 0 270)
			(size 0.4064 0.508)
			(layers "F.Cu" "F.Mask" "F.Paste")
			(net "P3V3_AUX")
		)
		(pad "6" smd rect
			(at 0.94996 -0.649986 270)
			(size 0.4064 0.508)
			(layers "F.Cu" "F.Mask" "F.Paste")
			(net "FM_GPU_PWR_EN_R1")
		)
	)
	(footprint ""
		(layer "F.Cu")
		(at 316.738 -356.87 90)
		(property "Reference" "PR69"
			(at 0 0 90)
			(layer "F.SilkS")
			(hide yes)
			(effects
				(font
					(size 1.27 1.27)
				)
			)
		)
		(property "Value" ""
			(at 0 0 90)
			(layer "F.Fab")
			(effects
				(font
					(size 1.27 1.27)
				)
			)
		)
		(duplicate_pad_numbers_are_jumpers no)
		(fp_line
			(start 0.7874 -0.4064)
			(end 0.7874 0.4064)
			(stroke
				(width 0.1524)
				(type default)
			)
			(layer "F.SilkS")
		)
		(fp_line
			(start -0.7874 -0.4064)
			(end 0.7874 -0.4064)
			(stroke
				(width 0.1524)
				(type default)
			)
			(layer "F.SilkS")
		)
		(fp_line
			(start 0.7874 0.4064)
			(end -0.7874 0.4064)
			(stroke
				(width 0.1524)
				(type default)
			)
			(layer "F.SilkS")
		)
		(fp_line
			(start -0.7874 0.4064)
			(end -0.7874 -0.4064)
			(stroke
				(width 0.1524)
				(type default)
			)
			(layer "F.SilkS")
		)
		(fp_line
			(start -0.12065 -0.305054)
			(end -0.12065 -0.2794)
			(stroke
				(width 0.1)
				(type default)
			)
			(layer "F.Fab")
		)
		(fp_line
			(start -0.67945 -0.305054)
			(end -0.12065 -0.305054)
			(stroke
				(width 0.1)
				(type default)
			)
			(layer "F.Fab")
		)
		(fp_line
			(start 0.67945 -0.3048)
			(end 0.67945 0.3048)
			(stroke
				(width 0.1)
				(type default)
			)
			(layer "F.Fab")
		)
		(fp_line
			(start 0.12065 -0.3048)
			(end 0.67945 -0.3048)
			(stroke
				(width 0.1)
				(type default)
			)
			(layer "F.Fab")
		)
		(fp_line
			(start 0.12065 -0.2794)
			(end 0.12065 -0.3048)
			(stroke
				(width 0.1)
				(type default)
			)
			(layer "F.Fab")
		)
		(fp_line
			(start -0.12065 -0.2794)
			(end 0.12065 -0.2794)
			(stroke
				(width 0.1)
				(type default)
			)
			(layer "F.Fab")
		)
		(fp_line
			(start 0.120396 0.2794)
			(end -0.12065 0.2794)
			(stroke
				(width 0.1)
				(type default)
			)
			(layer "F.Fab")
		)
		(fp_line
			(start -0.12065 0.2794)
			(end -0.12065 0.3048)
			(stroke
				(width 0.1)
				(type default)
			)
			(layer "F.Fab")
		)
		(fp_line
			(start 0.67945 0.3048)
			(end 0.120396 0.3048)
			(stroke
				(width 0.1)
				(type default)
			)
			(layer "F.Fab")
		)
		(fp_line
			(start 0.120396 0.3048)
			(end 0.120396 0.2794)
			(stroke
				(width 0.1)
				(type default)
			)
			(layer "F.Fab")
		)
		(fp_line
			(start -0.12065 0.3048)
			(end -0.67945 0.3048)
			(stroke
				(width 0.1)
				(type default)
			)
			(layer "F.Fab")
		)
		(fp_line
			(start -0.67945 0.3048)
			(end -0.67945 -0.305054)
			(stroke
				(width 0.1)
				(type default)
			)
			(layer "F.Fab")
		)
		(pad "1" smd circle
			(at -0.40005 0 90)
			(size 0 0)
			(layers "F.Cu" "F.Mask" "F.Paste")
			(net "VSENSE_PVDDIO_P0_DP")
		)
		(pad "2" smd circle
			(at 0.40005 0 90)
			(size 0 0)
			(layers "F.Cu" "F.Mask" "F.Paste")
			(net "VSENSE_PVDDIO_P0_VSEN1")
		)
	)
)
